#ISCELL
  cls sheet_a1 *
  *
#CELL
  passive ferritebead *
  page525_i10
#CELL
  discrete diode_2f *
  page525_i102
#CELL
  discrete diode_2f *
  page525_i104
#ISCELL
  cls vcc *
  page525_i105
#ISCELL
  cls vcc *
  page525_i107
#CELL
  passive ferritebead *
  page525_i108
#ISCELL
  cls gnd_sg *
  page525_i11
#CELL
  passive resistor *
  page525_i13
#CELL
  passive capacitor *
  page525_i14
#CELL
  passive capacitor *
  page525_i16
#ISCELL
  cls gnd_sg *
  page525_i17
#CELL
  passive capacitor *
  page525_i18
#ISCELL
  cls gnd_sg *
  page525_i19
#CELL
  passive capacitor *
  page525_i20
#CELL
  analog isl80101irajz_dfn10 *
  page525_i29
#ISCELL
  cls gnd_sg *
  page525_i30
#ISCELL
  cls gnd_sg *
  page525_i35
#ISCELL
  cls gnd_sg *
  page525_i55
#CELL
  passive capacitor *
  page525_i56
#ISCELL
  cls gnd_sg *
  page525_i6
#CELL
  passive capacitor *
  page525_i64
#CELL
  passive resistor *
  page525_i65
#CELL
  passive resistor *
  page525_i66
#CELL
  passive resistor *
  page525_i67
#CELL
  passive resistor *
  page525_i68
#ISCELL
  cls vcc *
  page525_i69
#CELL
  passive capacitor *
  page525_i7
#CELL
  passive capacitor *
  page525_i8
#ISCELL
  cls offpage_out *
  page525_i82
#ISCELL
  cls vcc *
  page525_i9
